# S9S_MB_2U (Grand Teton) — schematic netlist excerpt (pin names and nets, part order shuffled) for the footprints in the layout excerpt that follows; sources: Cadence DE-HDL packaged netlist, KiCad conversion of 03242023_DA0F0TMBIJ0_F0T_Motherboard_J_brd_V01_OCP.brd

C75  Q_CAP  2.2UF 6.3V 20% X6S  pkg C0402  page 112 : A = P3V3_AUX ; B = GND
R3348  Q_RES  1 1% CHIP  pkg 0603LF  page 217 : A = P3V3_AUX ; B = P3V3_AUX_FPGA_VCCIO1

(kicad_pcb
	(version 20260206)
	(generator "pcbnew")
	(generator_version "10.0")
	(general
		(thickness 1.6)
		(legacy_teardrops no)
	)
	(paper "A4")
	(title_block
		(title "03242023_DA0F0TMBIJ0_F0T_Motherboard_J_brd_V01_OCP.brd")
		(comment 1 "Grand Teton / footprints 5177-5178 of 6105")
	)
	(layers
		(0 "F.Cu" signal "TOP")
		(4 "In1.Cu" signal "GND")
		(6 "In2.Cu" signal "IN1")
		(8 "In3.Cu" signal "GND1")
		(10 "In4.Cu" signal "IN2")
		(12 "In5.Cu" signal "GND2")
		(14 "In6.Cu" signal "IN3")
		(16 "In7.Cu" signal "GND3")
		(18 "In8.Cu" signal "VCC")
		(20 "In9.Cu" signal "VCC1")
		(22 "In10.Cu" signal "GND4")
		(24 "In11.Cu" signal "IN4")
		(26 "In12.Cu" signal "GND5")
		(28 "In13.Cu" signal "IN5")
		(30 "In14.Cu" signal "GND6")
		(32 "In15.Cu" signal "IN6")
		(34 "In16.Cu" signal "GND7")
		(2 "B.Cu" signal "BOTTOM")
		(9 "F.Adhes" user "F.Adhesive")
		(11 "B.Adhes" user "B.Adhesive")
		(13 "F.Paste" user "Package Geometry/Pastemask Top")
		(15 "B.Paste" user "Package Geometry/Pastemask Bottom")
		(5 "F.SilkS" user "Ref Des/Silkscreen Top")
		(7 "B.SilkS" user "Ref Des/Silkscreen Bottom")
		(1 "F.Mask" user "Board Geometry/Soldermask Top")
		(3 "B.Mask" user "Board Geometry/Soldermask Bottom")
		(17 "Dwgs.User" user "User.Drawings")
		(19 "Cmts.User" user "User.Comments")
		(21 "Eco1.User" user "User.Eco1")
		(23 "Eco2.User" user "User.Eco2")
		(25 "Edge.Cuts" user "Board Geometry/Outline")
		(27 "Margin" user)
		(31 "F.CrtYd" user "Package Geometry/Place Bound Top")
		(29 "B.CrtYd" user "Package Geometry/Place Bound Bottom")
		(35 "F.Fab" user "Ref Des/Assembly Top")
		(33 "B.Fab" user "Ref Des/Assembly Bottom")
	)
	(footprint ""
		(layer "B.Cu")
		(at 174.29988 -123.916948 90)
		(property "Reference" "R3348"
			(at 0 0 90)
			(layer "B.SilkS")
			(hide yes)
			(effects
				(font
					(size 1.27 1.27)
				)
				(justify mirror)
			)
		)
		(property "Value" ""
			(at 0 0 90)
			(layer "B.Fab")
			(effects
				(font
					(size 1.27 1.27)
				)
				(justify mirror)
			)
		)
		(duplicate_pad_numbers_are_jumpers no)
		(fp_line
			(start 1.2954 -0.5842)
			(end -1.2954 -0.5842)
			(stroke
				(width 0.1524)
				(type default)
			)
			(layer "B.SilkS")
		)
		(fp_line
			(start -1.2954 -0.5842)
			(end -1.2954 0.5842)
			(stroke
				(width 0.1524)
				(type default)
			)
			(layer "B.SilkS")
		)
		(fp_line
			(start 1.2954 0.5842)
			(end 1.2954 -0.5842)
			(stroke
				(width 0.1524)
				(type default)
			)
			(layer "B.SilkS")
		)
		(fp_line
			(start -1.2954 0.5842)
			(end 1.2954 0.5842)
			(stroke
				(width 0.1524)
				(type default)
			)
			(layer "B.SilkS")
		)
		(fp_line
			(start 0.8636 -0.4572)
			(end -0.8636 -0.4572)
			(stroke
				(width 0.1)
				(type default)
			)
			(layer "B.Fab")
		)
		(fp_line
			(start -0.8636 -0.4572)
			(end -0.8636 -0.406654)
			(stroke
				(width 0.1)
				(type default)
			)
			(layer "B.Fab")
		)
		(fp_line
			(start 1.1938 -0.406654)
			(end 0.8636 -0.406654)
			(stroke
				(width 0.1)
				(type default)
			)
			(layer "B.Fab")
		)
		(fp_line
			(start 0.8636 -0.406654)
			(end 0.8636 -0.4572)
			(stroke
				(width 0.1)
				(type default)
			)
			(layer "B.Fab")
		)
		(fp_line
			(start -0.8636 -0.406654)
			(end -1.1938 -0.406654)
			(stroke
				(width 0.1)
				(type default)
			)
			(layer "B.Fab")
		)
		(fp_line
			(start -1.1938 -0.406654)
			(end -1.1938 0.4064)
			(stroke
				(width 0.1)
				(type default)
			)
			(layer "B.Fab")
		)
		(fp_line
			(start 1.1938 0.4064)
			(end 1.1938 -0.406654)
			(stroke
				(width 0.1)
				(type default)
			)
			(layer "B.Fab")
		)
		(fp_line
			(start 0.8636 0.4064)
			(end 1.1938 0.4064)
			(stroke
				(width 0.1)
				(type default)
			)
			(layer "B.Fab")
		)
		(fp_line
			(start -0.8636 0.4064)
			(end -0.8636 0.4572)
			(stroke
				(width 0.1)
				(type default)
			)
			(layer "B.Fab")
		)
		(fp_line
			(start -1.1938 0.4064)
			(end -0.8636 0.4064)
			(stroke
				(width 0.1)
				(type default)
			)
			(layer "B.Fab")
		)
		(fp_line
			(start 0.8636 0.4318)
			(end 0.8636 0.4064)
			(stroke
				(width 0.1)
				(type default)
			)
			(layer "B.Fab")
		)
		(fp_line
			(start 0.8636 0.4572)
			(end 0.8636 0.4318)
			(stroke
				(width 0.1)
				(type default)
			)
			(layer "B.Fab")
		)
		(fp_line
			(start -0.8636 0.4572)
			(end 0.8636 0.4572)
			(stroke
				(width 0.1)
				(type default)
			)
			(layer "B.Fab")
		)
		(pad "1" smd rect
			(at 0.7366 0)
			(size 0.7112 0.8128)
			(layers "B.Cu" "B.Mask" "B.Paste")
			(net "P3V3_AUX")
		)
		(pad "2" smd rect
			(at -0.7366 0)
			(size 0.7112 0.8128)
			(layers "B.Cu" "B.Mask" "B.Paste")
			(net "P3V3_AUX_FPGA_VCCIO1")
		)
	)
	(footprint ""
		(layer "B.Cu")
		(at 211.632546 -319.268856 180)
		(property "Reference" "C75"
			(at 0 0 0)
			(layer "B.SilkS")
			(hide yes)
			(effects
				(font
					(size 1.27 1.27)
				)
				(justify mirror)
			)
		)
		(property "Value" ""
			(at 0 0 0)
			(layer "B.Fab")
			(effects
				(font
					(size 1.27 1.27)
				)
				(justify mirror)
			)
		)
		(duplicate_pad_numbers_are_jumpers no)
		(fp_line
			(start 0.7874 0.4064)
			(end 0.7874 -0.4064)
			(stroke
				(width 0.1524)
				(type default)
			)
			(layer "B.SilkS")
		)
		(fp_line
			(start 0.7874 -0.4064)
			(end -0.7874 -0.4064)
			(stroke
				(width 0.1524)
				(type default)
			)
			(layer "B.SilkS")
		)
		(fp_line
			(start -0.7874 0.4064)
			(end 0.7874 0.4064)
			(stroke
				(width 0.1524)
				(type default)
			)
			(layer "B.SilkS")
		)
		(fp_line
			(start -0.7874 -0.4064)
			(end -0.7874 0.4064)
			(stroke
				(width 0.1524)
				(type default)
			)
			(layer "B.SilkS")
		)
		(fp_line
			(start 0.67945 0.3048)
			(end 0.67945 -0.305054)
			(stroke
				(width 0.1)
				(type default)
			)
			(layer "B.Fab")
		)
		(fp_line
			(start 0.67945 -0.305054)
			(end 0.12065 -0.305054)
			(stroke
				(width 0.1)
				(type default)
			)
			(layer "B.Fab")
		)
		(fp_line
			(start 0.12065 0.3048)
			(end 0.67945 0.3048)
			(stroke
				(width 0.1)
				(type default)
			)
			(layer "B.Fab")
		)
		(fp_line
			(start 0.12065 0.2794)
			(end 0.12065 0.3048)
			(stroke
				(width 0.1)
				(type default)
			)
			(layer "B.Fab")
		)
		(fp_line
			(start 0.12065 -0.2794)
			(end -0.12065 -0.2794)
			(stroke
				(width 0.1)
				(type default)
			)
			(layer "B.Fab")
		)
		(fp_line
			(start 0.12065 -0.305054)
			(end 0.12065 -0.2794)
			(stroke
				(width 0.1)
				(type default)
			)
			(layer "B.Fab")
		)
		(fp_line
			(start -0.120396 0.3048)
			(end -0.120396 0.2794)
			(stroke
				(width 0.1)
				(type default)
			)
			(layer "B.Fab")
		)
		(fp_line
			(start -0.120396 0.2794)
			(end 0.12065 0.2794)
			(stroke
				(width 0.1)
				(type default)
			)
			(layer "B.Fab")
		)
		(fp_line
			(start -0.12065 -0.2794)
			(end -0.12065 -0.3048)
			(stroke
				(width 0.1)
				(type default)
			)
			(layer "B.Fab")
		)
		(fp_line
			(start -0.12065 -0.3048)
			(end -0.67945 -0.3048)
			(stroke
				(width 0.1)
				(type default)
			)
			(layer "B.Fab")
		)
		(fp_line
			(start -0.67945 0.3048)
			(end -0.120396 0.3048)
			(stroke
				(width 0.1)
				(type default)
			)
			(layer "B.Fab")
		)
		(fp_line
			(start -0.67945 -0.3048)
			(end -0.67945 0.3048)
			(stroke
				(width 0.1)
				(type default)
			)
			(layer "B.Fab")
		)
		(pad "1" smd circle
			(at 0.40005 0)
			(size 0 0)
			(layers "B.Cu" "B.Mask" "B.Paste")
			(net "P3V3_AUX")
		)
		(pad "2" smd circle
			(at -0.40005 0)
			(size 0 0)
			(layers "B.Cu" "B.Mask" "B.Paste")
			(net "GND")
		)
	)
)
